# S9S_MB_2U (Grand Teton) — schematic netlist excerpt (pin names and nets, part order shuffled) for the footprints in the layout excerpt that follows; sources: Cadence DE-HDL packaged netlist, KiCad conversion of 03242023_DA0F0TMBIJ0_F0T_Motherboard_J_brd_V01_OCP.brd

C884  Q_CAP_DIFFBUS  DIFF BUS_0.22UF 6.3V 20% X6S  pkg C0201  page 174 : \1\ = P5E_CPU0_PE3_TX_C_DN<8> ; \2\ = P5E_CPU0_PE3_TX_DN<8>
PC1345  Q_CAP  0.1UF 25V 10% X7R  pkg 0402  page 270 : A = GND ; B = PVCCIN_CPU0_VREF
PC1258  Q_CAPP  560UF 6.3V 20% OSCON  pkg THLF  page 281 : A = PVPP_HBM_CPU0 ; B = GND

(kicad_pcb
	(version 20260206)
	(generator "pcbnew")
	(generator_version "10.0")
	(general
		(thickness 1.6)
		(legacy_teardrops no)
	)
	(paper "A4")
	(title_block
		(title "03242023_DA0F0TMBIJ0_F0T_Motherboard_J_brd_V01_OCP.brd")
		(comment 1 "Grand Teton / footprints 2750-2752 of 6105")
	)
	(layers
		(0 "F.Cu" signal "TOP")
		(4 "In1.Cu" signal "GND")
		(6 "In2.Cu" signal "IN1")
		(8 "In3.Cu" signal "GND1")
		(10 "In4.Cu" signal "IN2")
		(12 "In5.Cu" signal "GND2")
		(14 "In6.Cu" signal "IN3")
		(16 "In7.Cu" signal "GND3")
		(18 "In8.Cu" signal "VCC")
		(20 "In9.Cu" signal "VCC1")
		(22 "In10.Cu" signal "GND4")
		(24 "In11.Cu" signal "IN4")
		(26 "In12.Cu" signal "GND5")
		(28 "In13.Cu" signal "IN5")
		(30 "In14.Cu" signal "GND6")
		(32 "In15.Cu" signal "IN6")
		(34 "In16.Cu" signal "GND7")
		(2 "B.Cu" signal "BOTTOM")
		(9 "F.Adhes" user "F.Adhesive")
		(11 "B.Adhes" user "B.Adhesive")
		(13 "F.Paste" user "Package Geometry/Pastemask Top")
		(15 "B.Paste" user "Package Geometry/Pastemask Bottom")
		(5 "F.SilkS" user "Ref Des/Silkscreen Top")
		(7 "B.SilkS" user "Ref Des/Silkscreen Bottom")
		(1 "F.Mask" user "Board Geometry/Soldermask Top")
		(3 "B.Mask" user "Board Geometry/Soldermask Bottom")
		(17 "Dwgs.User" user "User.Drawings")
		(19 "Cmts.User" user "User.Comments")
		(21 "Eco1.User" user "User.Eco1")
		(23 "Eco2.User" user "User.Eco2")
		(25 "Edge.Cuts" user "Board Geometry/Outline")
		(27 "Margin" user)
		(31 "F.CrtYd" user "Package Geometry/Place Bound Top")
		(29 "B.CrtYd" user "Package Geometry/Place Bound Bottom")
		(35 "F.Fab" user "Ref Des/Assembly Top")
		(33 "B.Fab" user "Ref Des/Assembly Bottom")
	)
	(footprint ""
		(layer "F.Cu")
		(at 325.95312 -347.541342 -90)
		(property "Reference" "PC1345"
			(at 0 0 270)
			(layer "F.SilkS")
			(hide yes)
			(effects
				(font
					(size 1.27 1.27)
				)
			)
		)
		(property "Value" ""
			(at 0 0 270)
			(layer "F.Fab")
			(effects
				(font
					(size 1.27 1.27)
				)
			)
		)
		(duplicate_pad_numbers_are_jumpers no)
		(fp_line
			(start -0.7874 0.4064)
			(end -0.7874 -0.4064)
			(stroke
				(width 0.1524)
				(type default)
			)
			(layer "F.SilkS")
		)
		(fp_line
			(start 0.7874 0.4064)
			(end -0.7874 0.4064)
			(stroke
				(width 0.1524)
				(type default)
			)
			(layer "F.SilkS")
		)
		(fp_line
			(start -0.7874 -0.4064)
			(end 0.7874 -0.4064)
			(stroke
				(width 0.1524)
				(type default)
			)
			(layer "F.SilkS")
		)
		(fp_line
			(start 0.7874 -0.4064)
			(end 0.7874 0.4064)
			(stroke
				(width 0.1524)
				(type default)
			)
			(layer "F.SilkS")
		)
		(fp_line
			(start -0.67945 0.3048)
			(end -0.67945 -0.305054)
			(stroke
				(width 0.1)
				(type default)
			)
			(layer "F.Fab")
		)
		(fp_line
			(start -0.12065 0.3048)
			(end -0.67945 0.3048)
			(stroke
				(width 0.1)
				(type default)
			)
			(layer "F.Fab")
		)
		(fp_line
			(start 0.120396 0.3048)
			(end 0.120396 0.2794)
			(stroke
				(width 0.1)
				(type default)
			)
			(layer "F.Fab")
		)
		(fp_line
			(start 0.67945 0.3048)
			(end 0.120396 0.3048)
			(stroke
				(width 0.1)
				(type default)
			)
			(layer "F.Fab")
		)
		(fp_line
			(start -0.12065 0.2794)
			(end -0.12065 0.3048)
			(stroke
				(width 0.1)
				(type default)
			)
			(layer "F.Fab")
		)
		(fp_line
			(start 0.120396 0.2794)
			(end -0.12065 0.2794)
			(stroke
				(width 0.1)
				(type default)
			)
			(layer "F.Fab")
		)
		(fp_line
			(start -0.12065 -0.2794)
			(end 0.12065 -0.2794)
			(stroke
				(width 0.1)
				(type default)
			)
			(layer "F.Fab")
		)
		(fp_line
			(start 0.12065 -0.2794)
			(end 0.12065 -0.3048)
			(stroke
				(width 0.1)
				(type default)
			)
			(layer "F.Fab")
		)
		(fp_line
			(start 0.12065 -0.3048)
			(end 0.67945 -0.3048)
			(stroke
				(width 0.1)
				(type default)
			)
			(layer "F.Fab")
		)
		(fp_line
			(start 0.67945 -0.3048)
			(end 0.67945 0.3048)
			(stroke
				(width 0.1)
				(type default)
			)
			(layer "F.Fab")
		)
		(fp_line
			(start -0.67945 -0.305054)
			(end -0.12065 -0.305054)
			(stroke
				(width 0.1)
				(type default)
			)
			(layer "F.Fab")
		)
		(fp_line
			(start -0.12065 -0.305054)
			(end -0.12065 -0.2794)
			(stroke
				(width 0.1)
				(type default)
			)
			(layer "F.Fab")
		)
		(pad "1" smd circle
			(at -0.40005 0 270)
			(size 0 0)
			(layers "F.Cu" "F.Mask" "F.Paste")
			(net "GND")
		)
		(pad "2" smd circle
			(at 0.40005 0 270)
			(size 0 0)
			(layers "F.Cu" "F.Mask" "F.Paste")
			(net "PVCCIN_CPU0_VREF")
		)
	)
	(footprint ""
		(layer "F.Cu")
		(at 394.18641 -408.517344 -90)
		(property "Reference" "C884"
			(at 0 0 270)
			(layer "F.SilkS")
			(hide yes)
			(effects
				(font
					(size 1.27 1.27)
				)
			)
		)
		(property "Value" ""
			(at 0 0 270)
			(layer "F.Fab")
			(effects
				(font
					(size 1.27 1.27)
				)
			)
		)
		(duplicate_pad_numbers_are_jumpers no)
		(fp_line
			(start -0.299974 0.150114)
			(end -0.299974 -0.150114)
			(stroke
				(width 0.1)
				(type default)
			)
			(layer "F.Fab")
		)
		(fp_line
			(start 0.299974 0.150114)
			(end -0.299974 0.150114)
			(stroke
				(width 0.1)
				(type default)
			)
			(layer "F.Fab")
		)
		(fp_line
			(start -0.299974 -0.150114)
			(end 0.299974 -0.150114)
			(stroke
				(width 0.1)
				(type default)
			)
			(layer "F.Fab")
		)
		(fp_line
			(start 0.299974 -0.150114)
			(end 0.299974 0.150114)
			(stroke
				(width 0.1)
				(type default)
			)
			(layer "F.Fab")
		)
		(pad "1" smd rect
			(at -0.2667 0 270)
			(size 0.3048 0.381)
			(layers "F.Cu" "F.Mask" "F.Paste")
			(net "P5E_CPU0_PE3_TX_C_DN<8>")
		)
		(pad "2" smd rect
			(at 0.2667 0 270)
			(size 0.3048 0.381)
			(layers "F.Cu" "F.Mask" "F.Paste")
			(net "P5E_CPU0_PE3_TX_DN<8>")
		)
	)
	(footprint ""
		(layer "F.Cu")
		(at 381.750824 -368.140742)
		(property "Reference" "PC1258"
			(at 0 0 0)
			(layer "F.SilkS")
			(hide yes)
			(effects
				(font
					(size 1.27 1.27)
				)
			)
		)
		(property "Value" ""
			(at 0 0 0)
			(layer "F.Fab")
			(effects
				(font
					(size 1.27 1.27)
				)
			)
		)
		(duplicate_pad_numbers_are_jumpers no)
		(fp_line
			(start -3.400044 1.249934)
			(end 3.400044 1.249934)
			(stroke
				(width 0.1524)
				(type default)
			)
			(layer "F.SilkS")
		)
		(fp_circle
			(center 0 1.249934)
			(end 3.400044 1.249934)
			(stroke
				(width 0.1524)
				(type default)
			)
			(fill no)
			(layer "F.SilkS")
		)
		(fp_poly
			(pts
				(arc
					(start 3.400044 1.249934)
					(mid 0 4.649978)
					(end -3.400044 1.249934)
				)
			)
			(stroke
				(width 0)
				(type default)
			)
			(fill yes)
			(layer "F.SilkS")
		)
		(fp_circle
			(center 0 1.249934)
			(end 3.400044 1.249934)
			(stroke
				(width 0.1)
				(type default)
			)
			(fill no)
			(layer "F.Fab")
		)
		(pad "1" thru_hole rect
			(at 0 0)
			(size 1.524 1.524)
			(drill 1.016)
			(layers "*.Cu" "*.Mask")
			(remove_unused_layers no)
			(net "PVPP_HBM_CPU0")
			(clearance 0)
			(padstack
				(mode front_inner_back)
				(layer "Inner"
					(shape circle)
					(size 1.524 1.524)
					(clearance 0)
				)
				(layer "B.Cu"
					(shape rect)
					(size 1.524 1.524)
					(clearance 0)
				)
			)
		)
		(pad "2" thru_hole circle
			(at 0 2.500122)
			(size 1.524 1.524)
			(drill 1.016)
			(layers "*.Cu" "*.Mask")
			(remove_unused_layers no)
			(net "GND")
			(clearance 0)
		)
	)
)
